FILE_TYPE = CONNECTIVITY;
{Allegro Design Entry HDL 17.4-2019 S026 (4007227) 1/17/2022}
"PAGE_NUMBER" = 68;
0"NC";
1"PVDDCR_CPU0_P0\g";
2"PVDDCR_CPU0_P0\g";
3"GND\g";
4"GND\g";
5"PVDDCR_CPU0_P0\g";
6"GND\g";
7"PVDDCR_CPU0_P0\g";
8"GND\g";
9"GND\g";
10"PVDDCR_CPU0_P0\g";
11"PVDDCR_CPU1_P0\g";
12"GND\g";
13"PVDDCR_CPU1_P0\g";
14"GND\g";
15"PVDDCR_CPU1_P0\g";
16"GND\g";
17"PVDDCR_CPU1_P0\g";
18"GND\g";
19"PVDDCR_CPU1_P0\g";
20"GND\g";
%"Q_CAP"
"1","(-9000,2075)","0","pure_quanta","I1";
;
LOCATION"C2167"
$SEC"1"
CDS_SEC"1"
VALUE"22UF"
VOLTAGE"4V"
PACK_TYPE"C0402"
TOLERANCE"20%"
MATERIAL"X6S"
CDS_LIB"pure_quanta"
PART_NUMBER"CH622KMEB02";
"B"
$PN"2"4;
"A"
$PN"1"2;
%"Q_CAP"
"1","(-9000,4475)","0","pure_quanta","I10";
;
LOCATION"C246"
$SEC"1"
CDS_SEC"1"
MATERIAL"X6S"
TOLERANCE"20%"
VALUE"22UF"
VOLTAGE"4V"
PACK_TYPE"C0402"
CDS_LIB"pure_quanta"
PART_NUMBER"CH622KMEB02";
"B"
$PN"2"8;
"A"
$PN"1"7;
%"Q_CAP"
"1","(-2175,5250)","0","pure_quanta","I100";
;
LOCATION"C2231"
$SEC"1"
CDS_SEC"1"
MATERIAL"X6S"
TOLERANCE"20%"
VALUE"22UF"
VOLTAGE"4V"
PACK_TYPE"C0402"
CDS_LIB"pure_quanta"
PART_NUMBER"CH622KMEB02";
"B"
$PN"2"12;
"A"
$PN"1"11;
%"Q_CAP"
"1","(-1725,4475)","0","pure_quanta","I101";
;
LOCATION"C2238"
$SEC"1"
CDS_SEC"1"
MATERIAL"X6S"
TOLERANCE"20%"
VALUE"22UF"
VOLTAGE"4V"
PACK_TYPE"C0402"
CDS_LIB"pure_quanta"
PART_NUMBER"CH622KMEB02";
"B"
$PN"2"14;
"A"
$PN"1"13;
%"Q_CAP"
"1","(-1275,4475)","0","pure_quanta","I102";
;
LOCATION"C2244"
$SEC"1"
CDS_SEC"1"
MATERIAL"X6S"
TOLERANCE"20%"
VALUE"22UF"
VOLTAGE"4V"
PACK_TYPE"C0402"
CDS_LIB"pure_quanta"
PART_NUMBER"CH622KMEB02";
"B"
$PN"2"14;
"A"
$PN"1"13;
%"Q_CAP"
"1","(-1725,5250)","0","pure_quanta","I103";
;
LOCATION"C2237"
$SEC"1"
CDS_SEC"1"
MATERIAL"X6S"
TOLERANCE"20%"
VALUE"22UF"
VOLTAGE"4V"
PACK_TYPE"C0402"
CDS_LIB"pure_quanta"
PART_NUMBER"CH622KMEB02";
"B"
$PN"2"12;
"A"
$PN"1"11;
%"Q_CAP"
"1","(-1275,5250)","0","pure_quanta","I104";
;
LOCATION"C2243"
$SEC"1"
CDS_SEC"1"
MATERIAL"X6S"
TOLERANCE"20%"
VALUE"22UF"
VOLTAGE"4V"
PACK_TYPE"C0402"
CDS_LIB"pure_quanta"
PART_NUMBER"CH622KMEB02";
"B"
$PN"2"12;
"A"
$PN"1"11;
%"Q_CAP"
"1","(-825,4475)","0","pure_quanta","I105";
;
LOCATION"C2249"
$SEC"1"
CDS_SEC"1"
MATERIAL"X6S"
TOLERANCE"20%"
VALUE"22UF"
VOLTAGE"4V"
PACK_TYPE"C0402"
CDS_LIB"pure_quanta"
PART_NUMBER"CH622KMEB02";
"B"
$PN"2"14;
"A"
$PN"1"13;
%"Q_CAP"
"1","(-425,4475)","0","pure_quanta","I106";
;
LOCATION"C2254"
$SEC"1"
CDS_SEC"1"
MATERIAL"X6S"
TOLERANCE"20%"
VALUE"22UF"
VOLTAGE"4V"
PACK_TYPE"C0402"
CDS_LIB"pure_quanta"
PART_NUMBER"CH622KMEB02";
"B"
$PN"2"14;
"A"
$PN"1"13;
%"UNIVERSAL_GND"
"1","(-425,4875)","0","pure_quanta_power","I107";
;
CDS_LIB"pure_quanta_power"
HDL_POWER"GND";
"A"12;
%"Q_CAP"
"1","(-825,5250)","0","pure_quanta","I108";
;
LOCATION"C2248"
$SEC"1"
CDS_SEC"1"
MATERIAL"X6S"
TOLERANCE"20%"
VALUE"22UF"
VOLTAGE"4V"
PACK_TYPE"C0402"
CDS_LIB"pure_quanta"
PART_NUMBER"CH622KMEB02";
"B"
$PN"2"12;
"A"
$PN"1"11;
%"Q_CAP"
"1","(-425,5250)","0","pure_quanta","I109";
;
LOCATION"C2253"
$SEC"1"
CDS_SEC"1"
MATERIAL"X6S"
TOLERANCE"20%"
VALUE"22UF"
VOLTAGE"4V"
PACK_TYPE"C0402"
CDS_LIB"pure_quanta"
PART_NUMBER"CH622KMEB02";
"B"
$PN"2"12;
"A"
$PN"1"11;
%"UNIVERSAL_POWER"
"1","(-9000,4750)","0","pure_quanta_power","I11";
;
HDL_POWER"PVDDCR_CPU0_P0"
CDS_LIB"pure_quanta_power";
"A"7;
%"Q_CAP"
"1","(-6300,5250)","0","pure_quanta","I110";
;
LOCATION"C272"
$SEC"1"
CDS_SEC"1"
MATERIAL"X6S"
TOLERANCE"20%"
VALUE"22UF"
VOLTAGE"4V"
PACK_TYPE"C0402"
CDS_LIB"pure_quanta"
PART_NUMBER"CH622KMEB02";
"B"
$PN"2"9;
"A"
$PN"1"10;
%"Q_CAP"
"1","(-8550,4475)","0","pure_quanta","I12";
;
LOCATION"C252"
$SEC"1"
CDS_SEC"1"
MATERIAL"X6S"
TOLERANCE"20%"
VALUE"22UF"
VOLTAGE"4V"
PACK_TYPE"C0402"
CDS_LIB"pure_quanta"
PART_NUMBER"CH622KMEB02";
"B"
$PN"2"8;
"A"
$PN"1"7;
%"UNIVERSAL_POWER"
"1","(-9000,5525)","0","pure_quanta_power","I13";
;
HDL_POWER"PVDDCR_CPU0_P0"
CDS_LIB"pure_quanta_power";
"A"10;
%"Q_CAP"
"1","(-9000,5250)","0","pure_quanta","I14";
;
LOCATION"C245"
$SEC"1"
CDS_SEC"1"
MATERIAL"X6S"
TOLERANCE"20%"
VALUE"22UF"
VOLTAGE"4V"
PACK_TYPE"C0402"
CDS_LIB"pure_quanta"
PART_NUMBER"CH622KMEB02";
"B"
$PN"2"9;
"A"
$PN"1"10;
%"Q_CAP"
"1","(-8550,5250)","0","pure_quanta","I15";
;
LOCATION"C251"
$SEC"1"
CDS_SEC"1"
MATERIAL"X6S"
TOLERANCE"20%"
VALUE"22UF"
VOLTAGE"4V"
PACK_TYPE"C0402"
CDS_LIB"pure_quanta"
PART_NUMBER"CH622KMEB02";
"B"
$PN"2"9;
"A"
$PN"1"10;
%"Q_CAP"
"1","(-8100,2075)","0","pure_quanta","I16";
;
LOCATION"C2175"
$SEC"1"
CDS_SEC"1"
TOLERANCE"20%"
VALUE"22UF"
VOLTAGE"4V"
PACK_TYPE"C0402"
MATERIAL"X6S"
CDS_LIB"pure_quanta"
PART_NUMBER"CH622KMEB02";
"B"
$PN"2"4;
"A"
$PN"1"2;
%"Q_CAP"
"1","(-7650,2075)","0","pure_quanta","I17";
;
LOCATION"C10179"
$SEC"1"
CDS_SEC"1"
MATERIAL"X6S"
TOLERANCE"20%"
VALUE"22UF"
VOLTAGE"4V"
PACK_TYPE"C0402"
CDS_LIB"pure_quanta"
PART_NUMBER"CH622KMEB02";
"B"
$PN"2"4;
"A"
$PN"1"2;
%"UNIVERSAL_GND"
"1","(-7200,1675)","0","pure_quanta_power","I18";
;
CDS_LIB"pure_quanta_power"
HDL_POWER"GND";
"A"4;
%"Q_CAP"
"1","(-7200,2075)","0","pure_quanta","I19";
;
LOCATION"C2183"
$SEC"1"
CDS_SEC"1"
MATERIAL"X6S"
TOLERANCE"20%"
VALUE"22UF"
VOLTAGE"4V"
PACK_TYPE"C0402"
CDS_LIB"pure_quanta"
PART_NUMBER"CH622KMEB02";
"B"
$PN"2"4;
"A"
$PN"1"2;
%"Q_CAP"
"1","(-8550,2075)","0","pure_quanta","I2";
;
LOCATION"C2171"
$SEC"1"
CDS_SEC"1"
MATERIAL"X6S"
TOLERANCE"20%"
VALUE"22UF"
VOLTAGE"4V"
PACK_TYPE"C0402"
CDS_LIB"pure_quanta"
PART_NUMBER"CH622KMEB02";
"B"
$PN"2"4;
"A"
$PN"1"2;
%"Q_CAP"
"1","(-8100,2875)","0","pure_quanta","I20";
;
LOCATION"C2174"
$SEC"1"
CDS_SEC"1"
MATERIAL"X6S"
TOLERANCE"20%"
VALUE"22UF"
VOLTAGE"4V"
PACK_TYPE"C0402"
CDS_LIB"pure_quanta"
PART_NUMBER"CH622KMEB02";
"B"
$PN"2"3;
"A"
$PN"1"1;
%"Q_CAP"
"1","(-7650,2875)","0","pure_quanta","I21";
;
LOCATION"C2178"
$SEC"1"
CDS_SEC"1"
MATERIAL"X6S"
TOLERANCE"20%"
VALUE"22UF"
VOLTAGE"4V"
PACK_TYPE"C0402"
CDS_LIB"pure_quanta"
PART_NUMBER"CH622KMEB02";
"B"
$PN"2"3;
"A"
$PN"1"1;
%"Q_CAP"
"1","(-8100,3675)","0","pure_quanta","I22";
;
LOCATION"C2173"
$SEC"1"
CDS_SEC"1"
MATERIAL"X6S"
TOLERANCE"20%"
VALUE"22UF"
VOLTAGE"4V"
PACK_TYPE"C0402"
CDS_LIB"pure_quanta"
PART_NUMBER"CH622KMEB02";
"B"
$PN"2"6;
"A"
$PN"1"5;
%"Q_CAP"
"1","(-7650,3675)","0","pure_quanta","I23";
;
LOCATION"C2177"
$SEC"1"
CDS_SEC"1"
MATERIAL"X6S"
TOLERANCE"20%"
VALUE"22UF"
VOLTAGE"4V"
PACK_TYPE"C0402"
CDS_LIB"pure_quanta"
PART_NUMBER"CH622KMEB02";
"B"
$PN"2"6;
"A"
$PN"1"5;
%"Q_CAP"
"1","(-7200,2875)","0","pure_quanta","I24";
;
LOCATION"C2182"
$SEC"1"
CDS_SEC"1"
MATERIAL"X6S"
TOLERANCE"20%"
VALUE"22UF"
VOLTAGE"4V"
PACK_TYPE"C0402"
CDS_LIB"pure_quanta"
PART_NUMBER"CH622KMEB02";
"B"
$PN"2"3;
"A"
$PN"1"1;
%"Q_CAP"
"1","(-7200,3675)","0","pure_quanta","I25";
;
LOCATION"C2181"
$SEC"1"
CDS_SEC"1"
MATERIAL"X6S"
TOLERANCE"20%"
VALUE"22UF"
VOLTAGE"4V"
PACK_TYPE"C0402"
CDS_LIB"pure_quanta"
PART_NUMBER"CH622KMEB02";
"B"
$PN"2"6;
"A"
$PN"1"5;
%"Q_CAP"
"1","(-6750,2875)","0","pure_quanta","I26";
;
LOCATION"C2186"
$SEC"1"
CDS_SEC"1"
MATERIAL"X6S"
TOLERANCE"20%"
VALUE"22UF"
VOLTAGE"4V"
PACK_TYPE"C0402"
CDS_LIB"pure_quanta"
PART_NUMBER"CH622KMEB02";
"B"
$PN"2"3;
"A"
$PN"1"1;
%"Q_CAP"
"1","(-6300,2875)","0","pure_quanta","I27";
;
LOCATION"C2190"
$SEC"1"
CDS_SEC"1"
MATERIAL"X6S"
TOLERANCE"20%"
VALUE"22UF"
VOLTAGE"4V"
PACK_TYPE"C0402"
CDS_LIB"pure_quanta"
PART_NUMBER"CH622KMEB02";
"B"
$PN"2"3;
"A"
$PN"1"1;
%"Q_CAP"
"1","(-6750,3675)","0","pure_quanta","I28";
;
LOCATION"C2185"
$SEC"1"
CDS_SEC"1"
MATERIAL"X6S"
TOLERANCE"20%"
VALUE"22UF"
VOLTAGE"4V"
PACK_TYPE"C0402"
CDS_LIB"pure_quanta"
PART_NUMBER"CH622KMEB02";
"B"
$PN"2"6;
"A"
$PN"1"5;
%"Q_CAP"
"1","(-6300,3675)","0","pure_quanta","I29";
;
LOCATION"C2189"
$SEC"1"
CDS_SEC"1"
MATERIAL"X6S"
TOLERANCE"20%"
VALUE"22UF"
VOLTAGE"4V"
PACK_TYPE"C0402"
CDS_LIB"pure_quanta"
PART_NUMBER"CH622KMEB02";
"B"
$PN"2"6;
"A"
$PN"1"5;
%"UNIVERSAL_POWER"
"1","(-9000,2350)","0","pure_quanta_power","I3";
;
HDL_POWER"PVDDCR_CPU0_P0"
CDS_LIB"pure_quanta_power";
"A"2;
%"Q_CAP"
"1","(-4425,2075)","0","pure_quanta","I30";
;
LOCATION"C2205"
$SEC"1"
CDS_SEC"1"
MATERIAL"X6S"
TOLERANCE"20%"
VALUE"22UF"
VOLTAGE"4V"
PACK_TYPE"C0402"
CDS_LIB"pure_quanta"
PART_NUMBER"CH622KMEB02";
"B"
$PN"2"20;
"A"
$PN"1"19;
%"Q_CAP"
"1","(-5850,2875)","0","pure_quanta","I31";
;
LOCATION"C2193"
$SEC"1"
CDS_SEC"1"
MATERIAL"X6S"
TOLERANCE"20%"
VALUE"22UF"
VOLTAGE"4V"
PACK_TYPE"C0402"
CDS_LIB"pure_quanta"
PART_NUMBER"CH622KMEB02";
"B"
$PN"2"3;
"A"
$PN"1"1;
%"Q_CAP"
"1","(-5400,2875)","0","pure_quanta","I32";
;
LOCATION"C2196"
$SEC"1"
CDS_SEC"1"
MATERIAL"X6S"
TOLERANCE"20%"
VALUE"22UF"
VOLTAGE"4V"
PACK_TYPE"C0402"
CDS_LIB"pure_quanta"
PART_NUMBER"CH622KMEB02";
"B"
$PN"2"3;
"A"
$PN"1"1;
%"Q_CAP"
"1","(-5850,3675)","0","pure_quanta","I33";
;
LOCATION"C2192"
$SEC"1"
CDS_SEC"1"
MATERIAL"X6S"
TOLERANCE"20%"
VALUE"22UF"
VOLTAGE"4V"
PACK_TYPE"C0402"
CDS_LIB"pure_quanta"
PART_NUMBER"CH622KMEB02";
"B"
$PN"2"6;
"A"
$PN"1"5;
%"Q_CAP"
"1","(-5400,3675)","0","pure_quanta","I34";
;
LOCATION"C2195"
$SEC"1"
CDS_SEC"1"
MATERIAL"X6S"
TOLERANCE"20%"
VALUE"22UF"
VOLTAGE"4V"
PACK_TYPE"C0402"
CDS_LIB"pure_quanta"
PART_NUMBER"CH622KMEB02";
"B"
$PN"2"6;
"A"
$PN"1"5;
%"UNIVERSAL_GND"
"1","(-5000,2500)","0","pure_quanta_power","I35";
;
CDS_LIB"pure_quanta_power"
HDL_POWER"GND";
"A"3;
%"Q_CAP"
"1","(-5000,2875)","0","pure_quanta","I36";
;
LOCATION"C2199"
$SEC"1"
CDS_SEC"1"
MATERIAL"X6S"
TOLERANCE"20%"
VALUE"22UF"
VOLTAGE"4V"
PACK_TYPE"C0402"
CDS_LIB"pure_quanta"
PART_NUMBER"CH622KMEB02";
"B"
$PN"2"3;
"A"
$PN"1"1;
%"UNIVERSAL_POWER"
"1","(-4425,2350)","0","pure_quanta_power","I37";
;
HDL_POWER"PVDDCR_CPU1_P0"
CDS_LIB"pure_quanta_power";
"A"19;
%"Q_CAP"
"1","(-4425,2875)","0","pure_quanta","I38";
;
LOCATION"C2204"
$SEC"1"
CDS_SEC"1"
MATERIAL"X6S"
TOLERANCE"20%"
VALUE"22UF"
VOLTAGE"4V"
PACK_TYPE"C0402"
CDS_LIB"pure_quanta"
PART_NUMBER"CH622KMEB02";
"B"
$PN"2"18;
"A"
$PN"1"17;
%"UNIVERSAL_GND"
"1","(-5000,3300)","0","pure_quanta_power","I39";
;
CDS_LIB"pure_quanta_power"
HDL_POWER"GND";
"A"6;
%"Q_CAP"
"1","(-9000,2875)","0","pure_quanta","I4";
;
LOCATION"C2166"
$SEC"1"
CDS_SEC"1"
MATERIAL"X6S"
TOLERANCE"20%"
VALUE"22UF"
VOLTAGE"4V"
PACK_TYPE"C0402"
CDS_LIB"pure_quanta"
PART_NUMBER"CH622KMEB02";
"B"
$PN"2"3;
"A"
$PN"1"1;
%"Q_CAP"
"1","(-5000,3675)","0","pure_quanta","I40";
;
LOCATION"C2198"
$SEC"1"
CDS_SEC"1"
MATERIAL"X6S"
TOLERANCE"20%"
VALUE"22UF"
VOLTAGE"4V"
PACK_TYPE"C0402"
CDS_LIB"pure_quanta"
PART_NUMBER"CH622KMEB02";
"B"
$PN"2"6;
"A"
$PN"1"5;
%"UNIVERSAL_GND"
"1","(-5000,4100)","0","pure_quanta_power","I41";
;
CDS_LIB"pure_quanta_power"
HDL_POWER"GND";
"A"8;
%"UNIVERSAL_POWER"
"1","(-4425,3150)","0","pure_quanta_power","I42";
;
HDL_POWER"PVDDCR_CPU1_P0"
CDS_LIB"pure_quanta_power";
"A"17;
%"Q_CAP"
"1","(-4425,3675)","0","pure_quanta","I43";
;
LOCATION"C2203"
$SEC"1"
CDS_SEC"1"
MATERIAL"X6S"
TOLERANCE"20%"
VALUE"22UF"
VOLTAGE"4V"
PACK_TYPE"C0402"
CDS_LIB"pure_quanta"
PART_NUMBER"CH622KMEB02";
"B"
$PN"2"16;
"A"
$PN"1"15;
%"UNIVERSAL_POWER"
"1","(-4425,3950)","0","pure_quanta_power","I44";
;
HDL_POWER"PVDDCR_CPU1_P0"
CDS_LIB"pure_quanta_power";
"A"15;
%"Q_CAP"
"1","(-8100,4475)","0","pure_quanta","I45";
;
LOCATION"C1922"
$SEC"1"
CDS_SEC"1"
MATERIAL"X6S"
TOLERANCE"20%"
VALUE"22UF"
VOLTAGE"4V"
PACK_TYPE"C0402"
CDS_LIB"pure_quanta"
PART_NUMBER"CH622KMEB02";
"B"
$PN"2"8;
"A"
$PN"1"7;
%"Q_CAP"
"1","(-7650,4475)","0","pure_quanta","I46";
;
LOCATION"C263"
$SEC"1"
CDS_SEC"1"
MATERIAL"X6S"
TOLERANCE"20%"
VALUE"22UF"
VOLTAGE"4V"
PACK_TYPE"C0402"
CDS_LIB"pure_quanta"
PART_NUMBER"CH622KMEB02";
"B"
$PN"2"8;
"A"
$PN"1"7;
%"Q_CAP"
"1","(-8100,5250)","0","pure_quanta","I47";
;
LOCATION"C4178"
$SEC"1"
CDS_SEC"1"
MATERIAL"X6S"
TOLERANCE"20%"
VALUE"22UF"
VOLTAGE"4V"
PACK_TYPE"C0402"
CDS_LIB"pure_quanta"
PART_NUMBER"CH622KMEB02";
"B"
$PN"2"9;
"A"
$PN"1"10;
%"Q_CAP"
"1","(-7650,5250)","0","pure_quanta","I48";
;
LOCATION"C4179"
$SEC"1"
CDS_SEC"1"
MATERIAL"X6S"
TOLERANCE"20%"
VALUE"22UF"
VOLTAGE"4V"
PACK_TYPE"C0402"
CDS_LIB"pure_quanta"
PART_NUMBER"CH622KMEB02";
"B"
$PN"2"9;
"A"
$PN"1"10;
%"Q_CAP"
"1","(-7200,4475)","0","pure_quanta","I49";
;
LOCATION"C268"
$SEC"1"
CDS_SEC"1"
MATERIAL"X6S"
TOLERANCE"20%"
VALUE"22UF"
VOLTAGE"4V"
PACK_TYPE"C0402"
CDS_LIB"pure_quanta"
PART_NUMBER"CH622KMEB02";
"B"
$PN"2"8;
"A"
$PN"1"7;
%"Q_CAP"
"1","(-8550,2875)","0","pure_quanta","I5";
;
LOCATION"C2170"
$SEC"1"
CDS_SEC"1"
MATERIAL"X6S"
TOLERANCE"20%"
VALUE"22UF"
VOLTAGE"4V"
PACK_TYPE"C0402"
CDS_LIB"pure_quanta"
PART_NUMBER"CH622KMEB02";
"B"
$PN"2"3;
"A"
$PN"1"1;
%"Q_CAP"
"1","(-7200,5250)","0","pure_quanta","I50";
;
LOCATION"C267"
$SEC"1"
CDS_SEC"1"
MATERIAL"X6S"
TOLERANCE"20%"
VALUE"22UF"
VOLTAGE"4V"
PACK_TYPE"C0402"
CDS_LIB"pure_quanta"
PART_NUMBER"CH622KMEB02";
"B"
$PN"2"9;
"A"
$PN"1"10;
%"Q_CAP"
"1","(-6750,4475)","0","pure_quanta","I51";
;
LOCATION"C271"
$SEC"1"
CDS_SEC"1"
MATERIAL"X6S"
TOLERANCE"20%"
VALUE"22UF"
VOLTAGE"4V"
PACK_TYPE"C0402"
CDS_LIB"pure_quanta"
PART_NUMBER"CH622KMEB02";
"B"
$PN"2"8;
"A"
$PN"1"7;
%"Q_CAP"
"1","(-6300,4475)","0","pure_quanta","I52";
;
LOCATION"C273"
$SEC"1"
CDS_SEC"1"
MATERIAL"X6S"
TOLERANCE"20%"
VALUE"22UF"
VOLTAGE"4V"
PACK_TYPE"C0402"
CDS_LIB"pure_quanta"
PART_NUMBER"CH622KMEB02";
"B"
$PN"2"8;
"A"
$PN"1"7;
%"Q_CAP"
"1","(-6750,5250)","0","pure_quanta","I53";
;
LOCATION"C270"
$SEC"1"
CDS_SEC"1"
MATERIAL"X6S"
TOLERANCE"20%"
VALUE"22UF"
VOLTAGE"4V"
PACK_TYPE"C0402"
CDS_LIB"pure_quanta"
PART_NUMBER"CH622KMEB02";
"B"
$PN"2"9;
"A"
$PN"1"10;
%"Q_CAP"
"1","(-5850,4475)","0","pure_quanta","I54";
;
LOCATION"C275"
$SEC"1"
CDS_SEC"1"
MATERIAL"X6S"
TOLERANCE"20%"
VALUE"22UF"
VOLTAGE"4V"
PACK_TYPE"C0402"
CDS_LIB"pure_quanta"
PART_NUMBER"CH622KMEB02";
"B"
$PN"2"8;
"A"
$PN"1"7;
%"Q_CAP"
"1","(-5400,4475)","0","pure_quanta","I55";
;
LOCATION"C277"
$SEC"1"
CDS_SEC"1"
MATERIAL"X6S"
TOLERANCE"20%"
VALUE"22UF"
VOLTAGE"4V"
PACK_TYPE"C0402"
CDS_LIB"pure_quanta"
PART_NUMBER"CH622KMEB02";
"B"
$PN"2"8;
"A"
$PN"1"7;
%"Q_CAP"
"1","(-5850,5250)","0","pure_quanta","I56";
;
LOCATION"C274"
$SEC"1"
CDS_SEC"1"
MATERIAL"X6S"
TOLERANCE"20%"
VALUE"22UF"
VOLTAGE"4V"
PACK_TYPE"C0402"
CDS_LIB"pure_quanta"
PART_NUMBER"CH622KMEB02";
"B"
$PN"2"9;
"A"
$PN"1"10;
%"Q_CAP"
"1","(-5400,5250)","0","pure_quanta","I57";
;
LOCATION"C276"
$SEC"1"
CDS_SEC"1"
MATERIAL"X6S"
TOLERANCE"20%"
VALUE"22UF"
VOLTAGE"4V"
PACK_TYPE"C0402"
CDS_LIB"pure_quanta"
PART_NUMBER"CH622KMEB02";
"B"
$PN"2"9;
"A"
$PN"1"10;
%"Q_CAP"
"1","(-5000,4475)","0","pure_quanta","I58";
;
LOCATION"C279"
$SEC"1"
CDS_SEC"1"
MATERIAL"X6S"
TOLERANCE"20%"
VALUE"22UF"
VOLTAGE"4V"
PACK_TYPE"C0402"
CDS_LIB"pure_quanta"
PART_NUMBER"CH622KMEB02";
"B"
$PN"2"8;
"A"
$PN"1"7;
%"UNIVERSAL_GND"
"1","(-5000,4875)","0","pure_quanta_power","I59";
;
CDS_LIB"pure_quanta_power"
HDL_POWER"GND";
"A"9;
%"UNIVERSAL_POWER"
"1","(-9000,3150)","0","pure_quanta_power","I6";
;
HDL_POWER"PVDDCR_CPU0_P0"
CDS_LIB"pure_quanta_power";
"A"1;
%"Q_CAP"
"1","(-4425,4475)","0","pure_quanta","I60";
;
LOCATION"C2202"
$SEC"1"
CDS_SEC"1"
MATERIAL"X6S"
TOLERANCE"20%"
VALUE"22UF"
VOLTAGE"4V"
PACK_TYPE"C0402"
CDS_LIB"pure_quanta"
PART_NUMBER"CH622KMEB02";
"B"
$PN"2"14;
"A"
$PN"1"13;
%"UNIVERSAL_POWER"
"1","(-4425,4750)","0","pure_quanta_power","I61";
;
HDL_POWER"PVDDCR_CPU1_P0"
CDS_LIB"pure_quanta_power";
"A"13;
%"Q_CAP"
"1","(-5000,5250)","0","pure_quanta","I62";
;
LOCATION"C278"
$SEC"1"
CDS_SEC"1"
MATERIAL"X6S"
TOLERANCE"20%"
VALUE"22UF"
VOLTAGE"4V"
PACK_TYPE"C0402"
CDS_LIB"pure_quanta"
PART_NUMBER"CH622KMEB02";
"B"
$PN"2"9;
"A"
$PN"1"10;
%"Q_CAP"
"1","(-4425,5250)","0","pure_quanta","I63";
;
LOCATION"C2201"
$SEC"1"
CDS_SEC"1"
MATERIAL"X6S"
TOLERANCE"20%"
VALUE"22UF"
VOLTAGE"4V"
PACK_TYPE"C0402"
CDS_LIB"pure_quanta"
PART_NUMBER"CH622KMEB02";
"B"
$PN"2"12;
"A"
$PN"1"11;
%"UNIVERSAL_POWER"
"1","(-4425,5525)","0","pure_quanta_power","I64";
;
HDL_POWER"PVDDCR_CPU1_P0"
CDS_LIB"pure_quanta_power";
"A"11;
%"Q_CAP"
"1","(-3975,2075)","0","pure_quanta","I65";
;
LOCATION"C2211"
$SEC"1"
CDS_SEC"1"
MATERIAL"X6S"
TOLERANCE"20%"
VALUE"22UF"
VOLTAGE"4V"
PACK_TYPE"C0402"
CDS_LIB"pure_quanta"
PART_NUMBER"CH622KMEB02";
"B"
$PN"2"20;
"A"
$PN"1"19;
%"Q_CAP"
"1","(-3525,2075)","0","pure_quanta","I66";
;
LOCATION"C2217"
$SEC"1"
CDS_SEC"1"
MATERIAL"X6S"
TOLERANCE"20%"
VALUE"22UF"
VOLTAGE"4V"
PACK_TYPE"C0402"
CDS_LIB"pure_quanta"
PART_NUMBER"CH622KMEB02";
"B"
$PN"2"20;
"A"
$PN"1"19;
%"Q_CAP"
"1","(-3075,2075)","0","pure_quanta","I67";
;
LOCATION"C2223"
$SEC"1"
CDS_SEC"1"
MATERIAL"X6S"
TOLERANCE"20%"
VALUE"22UF"
VOLTAGE"4V"
PACK_TYPE"C0402"
CDS_LIB"pure_quanta"
PART_NUMBER"CH622KMEB02";
"B"
$PN"2"20;
"A"
$PN"1"19;
%"UNIVERSAL_GND"
"1","(-2625,1725)","0","pure_quanta_power","I68";
;
CDS_LIB"pure_quanta_power"
HDL_POWER"GND";
"A"20;
%"Q_CAP"
"1","(-2625,2075)","0","pure_quanta","I69";
;
LOCATION"C2229"
$SEC"1"
CDS_SEC"1"
MATERIAL"X6S"
TOLERANCE"20%"
VALUE"22UF"
VOLTAGE"4V"
PACK_TYPE"C0402"
CDS_LIB"pure_quanta"
PART_NUMBER"CH622KMEB02";
"B"
$PN"2"20;
"A"
$PN"1"19;
%"Q_CAP"
"1","(-9000,3675)","0","pure_quanta","I7";
;
LOCATION"C2165"
$SEC"1"
CDS_SEC"1"
MATERIAL"X6S"
TOLERANCE"20%"
VALUE"22UF"
VOLTAGE"4V"
PACK_TYPE"C0402"
CDS_LIB"pure_quanta"
PART_NUMBER"CH622KMEB02";
"B"
$PN"2"6;
"A"
$PN"1"5;
%"Q_CAP"
"1","(-3975,2875)","0","pure_quanta","I70";
;
LOCATION"C2210"
$SEC"1"
CDS_SEC"1"
MATERIAL"X6S"
TOLERANCE"20%"
VALUE"22UF"
VOLTAGE"4V"
PACK_TYPE"C0402"
CDS_LIB"pure_quanta"
PART_NUMBER"CH622KMEB02";
"B"
$PN"2"18;
"A"
$PN"1"17;
%"Q_CAP"
"1","(-3525,2875)","0","pure_quanta","I71";
;
LOCATION"C2216"
$SEC"1"
CDS_SEC"1"
MATERIAL"X6S"
TOLERANCE"20%"
VALUE"22UF"
VOLTAGE"4V"
PACK_TYPE"C0402"
CDS_LIB"pure_quanta"
PART_NUMBER"CH622KMEB02";
"B"
$PN"2"18;
"A"
$PN"1"17;
%"Q_CAP"
"1","(-3975,3675)","0","pure_quanta","I72";
;
LOCATION"C2209"
$SEC"1"
CDS_SEC"1"
MATERIAL"X6S"
TOLERANCE"20%"
VALUE"22UF"
VOLTAGE"4V"
PACK_TYPE"C0402"
CDS_LIB"pure_quanta"
PART_NUMBER"CH622KMEB02";
"B"
$PN"2"16;
"A"
$PN"1"15;
%"Q_CAP"
"1","(-3525,3675)","0","pure_quanta","I73";
;
LOCATION"C2215"
$SEC"1"
CDS_SEC"1"
MATERIAL"X6S"
TOLERANCE"20%"
VALUE"22UF"
VOLTAGE"4V"
PACK_TYPE"C0402"
CDS_LIB"pure_quanta"
PART_NUMBER"CH622KMEB02";
"B"
$PN"2"16;
"A"
$PN"1"15;
%"Q_CAP"
"1","(-3075,2875)","0","pure_quanta","I74";
;
LOCATION"C2222"
$SEC"1"
CDS_SEC"1"
MATERIAL"X6S"
TOLERANCE"20%"
VALUE"22UF"
VOLTAGE"4V"
PACK_TYPE"C0402"
CDS_LIB"pure_quanta"
PART_NUMBER"CH622KMEB02";
"B"
$PN"2"18;
"A"
$PN"1"17;
%"Q_CAP"
"1","(-2625,2875)","0","pure_quanta","I75";
;
LOCATION"C2228"
$SEC"1"
CDS_SEC"1"
MATERIAL"X6S"
TOLERANCE"20%"
VALUE"22UF"
VOLTAGE"4V"
PACK_TYPE"C0402"
CDS_LIB"pure_quanta"
PART_NUMBER"CH622KMEB02";
"B"
$PN"2"18;
"A"
$PN"1"17;
%"Q_CAP"
"1","(-2175,2875)","0","pure_quanta","I76";
;
LOCATION"C2234"
$SEC"1"
CDS_SEC"1"
MATERIAL"X6S"
TOLERANCE"20%"
VALUE"22UF"
VOLTAGE"4V"
PACK_TYPE"C0402"
CDS_LIB"pure_quanta"
PART_NUMBER"CH622KMEB02";
"B"
$PN"2"18;
"A"
$PN"1"17;
%"Q_CAP"
"1","(-3075,3675)","0","pure_quanta","I77";
;
LOCATION"C2221"
$SEC"1"
CDS_SEC"1"
MATERIAL"X6S"
TOLERANCE"20%"
VALUE"22UF"
VOLTAGE"4V"
PACK_TYPE"C0402"
CDS_LIB"pure_quanta"
PART_NUMBER"CH622KMEB02";
"B"
$PN"2"16;
"A"
$PN"1"15;
%"Q_CAP"
"1","(-2625,3675)","0","pure_quanta","I78";
;
LOCATION"C2227"
$SEC"1"
CDS_SEC"1"
MATERIAL"X6S"
TOLERANCE"20%"
VALUE"22UF"
VOLTAGE"4V"
PACK_TYPE"C0402"
CDS_LIB"pure_quanta"
PART_NUMBER"CH622KMEB02";
"B"
$PN"2"16;
"A"
$PN"1"15;
%"Q_CAP"
"1","(-2175,3675)","0","pure_quanta","I79";
;
LOCATION"C2233"
$SEC"1"
CDS_SEC"1"
MATERIAL"X6S"
TOLERANCE"20%"
VALUE"22UF"
VOLTAGE"4V"
PACK_TYPE"C0402"
CDS_LIB"pure_quanta"
PART_NUMBER"CH622KMEB02";
"B"
$PN"2"16;
"A"
$PN"1"15;
%"UNIVERSAL_POWER"
"1","(-9000,3950)","0","pure_quanta_power","I8";
;
HDL_POWER"PVDDCR_CPU0_P0"
CDS_LIB"pure_quanta_power";
"A"5;
%"Q_CAP"
"1","(-1725,2875)","0","pure_quanta","I80";
;
LOCATION"C2240"
$SEC"1"
CDS_SEC"1"
MATERIAL"X6S"
TOLERANCE"20%"
VALUE"22UF"
VOLTAGE"4V"
PACK_TYPE"C0402"
CDS_LIB"pure_quanta"
PART_NUMBER"CH622KMEB02";
"B"
$PN"2"18;
"A"
$PN"1"17;
%"Q_CAP"
"1","(-1275,2875)","0","pure_quanta","I81";
;
LOCATION"C2246"
$SEC"1"
CDS_SEC"1"
MATERIAL"X6S"
TOLERANCE"20%"
VALUE"22UF"
VOLTAGE"4V"
PACK_TYPE"C0402"
CDS_LIB"pure_quanta"
PART_NUMBER"CH622KMEB02";
"B"
$PN"2"18;
"A"
$PN"1"17;
%"Q_CAP"
"1","(-1725,3675)","0","pure_quanta","I82";
;
LOCATION"C2239"
$SEC"1"
CDS_SEC"1"
MATERIAL"X6S"
TOLERANCE"20%"
VALUE"22UF"
VOLTAGE"4V"
PACK_TYPE"C0402"
CDS_LIB"pure_quanta"
PART_NUMBER"CH622KMEB02";
"B"
$PN"2"16;
"A"
$PN"1"15;
%"Q_CAP"
"1","(-1275,3675)","0","pure_quanta","I83";
;
LOCATION"C2245"
$SEC"1"
CDS_SEC"1"
MATERIAL"X6S"
TOLERANCE"20%"
VALUE"22UF"
VOLTAGE"4V"
PACK_TYPE"C0402"
CDS_LIB"pure_quanta"
PART_NUMBER"CH622KMEB02";
"B"
$PN"2"16;
"A"
$PN"1"15;
%"Q_CAP"
"1","(-825,2875)","0","pure_quanta","I84";
;
LOCATION"C2251"
$SEC"1"
CDS_SEC"1"
MATERIAL"X6S"
TOLERANCE"20%"
VALUE"22UF"
VOLTAGE"4V"
PACK_TYPE"C0402"
CDS_LIB"pure_quanta"
PART_NUMBER"CH622KMEB02";
"B"
$PN"2"18;
"A"
$PN"1"17;
%"UNIVERSAL_GND"
"1","(-425,2500)","0","pure_quanta_power","I85";
;
CDS_LIB"pure_quanta_power"
HDL_POWER"GND";
"A"18;
%"Q_CAP"
"1","(-425,2875)","0","pure_quanta","I86";
;
LOCATION"C2256"
$SEC"1"
CDS_SEC"1"
MATERIAL"X6S"
TOLERANCE"20%"
VALUE"22UF"
VOLTAGE"4V"
PACK_TYPE"C0402"
CDS_LIB"pure_quanta"
PART_NUMBER"CH622KMEB02";
"B"
$PN"2"18;
"A"
$PN"1"17;
%"Q_CAP"
"1","(-825,3675)","0","pure_quanta","I87";
;
LOCATION"C2250"
$SEC"1"
CDS_SEC"1"
MATERIAL"X6S"
TOLERANCE"20%"
VALUE"22UF"
VOLTAGE"4V"
PACK_TYPE"C0402"
CDS_LIB"pure_quanta"
PART_NUMBER"CH622KMEB02";
"B"
$PN"2"16;
"A"
$PN"1"15;
%"UNIVERSAL_GND"
"1","(-425,3300)","0","pure_quanta_power","I88";
;
CDS_LIB"pure_quanta_power"
HDL_POWER"GND";
"A"16;
%"Q_CAP"
"1","(-425,3675)","0","pure_quanta","I89";
;
LOCATION"C2255"
$SEC"1"
CDS_SEC"1"
MATERIAL"X6S"
TOLERANCE"20%"
VALUE"22UF"
VOLTAGE"4V"
PACK_TYPE"C0402"
CDS_LIB"pure_quanta"
PART_NUMBER"CH622KMEB02";
"B"
$PN"2"16;
"A"
$PN"1"15;
%"Q_CAP"
"1","(-8550,3675)","0","pure_quanta","I9";
;
LOCATION"C2169"
$SEC"1"
CDS_SEC"1"
MATERIAL"X6S"
TOLERANCE"20%"
VALUE"22UF"
VOLTAGE"4V"
PACK_TYPE"C0402"
CDS_LIB"pure_quanta"
PART_NUMBER"CH622KMEB02";
"B"
$PN"2"6;
"A"
$PN"1"5;
%"UNIVERSAL_GND"
"1","(-425,4100)","0","pure_quanta_power","I90";
;
CDS_LIB"pure_quanta_power"
HDL_POWER"GND";
"A"14;
%"Q_CAP"
"1","(-3975,4475)","0","pure_quanta","I91";
;
LOCATION"C2208"
$SEC"1"
CDS_SEC"1"
MATERIAL"X6S"
TOLERANCE"20%"
VALUE"22UF"
VOLTAGE"4V"
PACK_TYPE"C0402"
CDS_LIB"pure_quanta"
PART_NUMBER"CH622KMEB02";
"B"
$PN"2"14;
"A"
$PN"1"13;
%"Q_CAP"
"1","(-3525,4475)","0","pure_quanta","I92";
;
LOCATION"C2214"
$SEC"1"
CDS_SEC"1"
MATERIAL"X6S"
TOLERANCE"20%"
VALUE"22UF"
VOLTAGE"4V"
PACK_TYPE"C0402"
CDS_LIB"pure_quanta"
PART_NUMBER"CH622KMEB02";
"B"
$PN"2"14;
"A"
$PN"1"13;
%"Q_CAP"
"1","(-3975,5250)","0","pure_quanta","I93";
;
LOCATION"C2207"
$SEC"1"
CDS_SEC"1"
MATERIAL"X6S"
TOLERANCE"20%"
VALUE"22UF"
VOLTAGE"4V"
PACK_TYPE"C0402"
CDS_LIB"pure_quanta"
PART_NUMBER"CH622KMEB02";
"B"
$PN"2"12;
"A"
$PN"1"11;
%"Q_CAP"
"1","(-3525,5250)","0","pure_quanta","I94";
;
LOCATION"C2213"
$SEC"1"
CDS_SEC"1"
MATERIAL"X6S"
TOLERANCE"20%"
VALUE"22UF"
VOLTAGE"4V"
PACK_TYPE"C0402"
CDS_LIB"pure_quanta"
PART_NUMBER"CH622KMEB02";
"B"
$PN"2"12;
"A"
$PN"1"11;
%"Q_CAP"
"1","(-3075,4475)","0","pure_quanta","I95";
;
LOCATION"C2220"
$SEC"1"
CDS_SEC"1"
MATERIAL"X6S"
TOLERANCE"20%"
VALUE"22UF"
VOLTAGE"4V"
PACK_TYPE"C0402"
CDS_LIB"pure_quanta"
PART_NUMBER"CH622KMEB02";
"B"
$PN"2"14;
"A"
$PN"1"13;
%"Q_CAP"
"1","(-2625,4475)","0","pure_quanta","I96";
;
LOCATION"C2226"
$SEC"1"
CDS_SEC"1"
MATERIAL"X6S"
TOLERANCE"20%"
VALUE"22UF"
VOLTAGE"4V"
PACK_TYPE"C0402"
CDS_LIB"pure_quanta"
PART_NUMBER"CH622KMEB02";
"B"
$PN"2"14;
"A"
$PN"1"13;
%"Q_CAP"
"1","(-2175,4475)","0","pure_quanta","I97";
;
LOCATION"C2232"
$SEC"1"
CDS_SEC"1"
MATERIAL"X6S"
TOLERANCE"20%"
VALUE"22UF"
VOLTAGE"4V"
PACK_TYPE"C0402"
CDS_LIB"pure_quanta"
PART_NUMBER"CH622KMEB02";
"B"
$PN"2"14;
"A"
$PN"1"13;
%"Q_CAP"
"1","(-3075,5250)","0","pure_quanta","I98";
;
LOCATION"C2219"
$SEC"1"
CDS_SEC"1"
MATERIAL"X6S"
TOLERANCE"20%"
VALUE"22UF"
VOLTAGE"4V"
PACK_TYPE"C0402"
CDS_LIB"pure_quanta"
PART_NUMBER"CH622KMEB02";
"B"
$PN"2"12;
"A"
$PN"1"11;
%"Q_CAP"
"1","(-2625,5250)","0","pure_quanta","I99";
;
LOCATION"C2225"
$SEC"1"
CDS_SEC"1"
MATERIAL"X6S"
TOLERANCE"20%"
VALUE"22UF"
VOLTAGE"4V"
PACK_TYPE"C0402"
CDS_LIB"pure_quanta"
PART_NUMBER"CH622KMEB02";
"B"
$PN"2"12;
"A"
$PN"1"11;
END.
